FILE_TYPE = CONNECTIVITY;
{Allegro Design Entry HDL 16.6-p007 (v16-6-112F) 10/10/2012}
"PAGE_NUMBER" = 21;
0"NC";
1"PVCCIO_CPU0\g";
2"GND\g";
3"GND\g";
4"P3V3_STBY\g";
5"P3V3_STBY\g";
6"PVCCIO_CPU0\g";
7"M_D_CPU_VREF";
8"H_CPU0_MSMI_G_N";
9"M_E_CPU_VREF";
10"PWRGD_CPU0_DRAMPWROK_ABC_G";
11"PWRGD_CPU0_G";
12"CLK_100M_CPU0_BCLK2_DN";
13"A_CPU0_ABC_RCOMP2";
14"SVID_DIO1_CPU0";
15"FM_CPU0_PKGID2";
16"SVID_ALERT0_CPU0_R_N";
17"SVID_DIO0_CPU0_R";
18"SVID_CLK0_CPU0_R";
19"SVID_CLK1_CPU0_R";
20"SVID_DIO1_CPU0_R";
21"FM_CPU0_PKGID0";
22"PU_CPU0_SOCKET_ID_1";
23"PU_CPU0_SOCKET_ID_0";
24"FM_CPU0_PROC_ID0";
25"PU_CPU0_TSC_SYNC";
26"FM_CPU0_SM_WP";
27"TP_NMI_CPU0";
28"M_B_CPU_VREF";
29"SMB_PIROM_CPU0_SCL";
30"SMB_PIROM_CPU0_SDA";
31"SMB_CPU0_PE_HP_GTL_SCL";
32"SMB_CPU0_PE_HP_GTL_SDA";
33"XDP_CPU_OBSFN_B1_MBP7_N";
34"TP_XDP_CPU0_OBSDATA_A3_MBP5_N";
35"TP_XDP_CPU0_OBSDATA_A2_MBP4_N";
36"H_CPU0_MEMDEF_MEMHOT_G_N";
37"M_F_CPU_VREF";
38"H_CPU0_MEMABC_MEMHOT_G_N";
39"M_DEF_RST_N";
40"PWRGD_CPU0_DRAMPWROK_DEF_G";
41"XDP_CPU_TRST_N";
42"XDP_CPU_TCK0";
43"XDP_CPU_MBP0_N";
44"TP_XDP_CPU0_OBSDATA_A0_MBP2_N";
45"TP_XDP_CPU0_OBSDATA_A1_MBP3_N";
46"A_CPU0_MCP01_RBIAS";
47"SMB_DDR_ABC_SDA_G_R";
48"SMB_DDR_DEF_SDA_G_R";
49"SMB_DDR_ABC_SCL_G_R";
50"SMB_DDR_DEF_SCL_G_R";
51"CLK_100M_CPU0_BCLK2_DP";
52"CLK_100M_CPU0_BCLK1_DP";
53"CLK_100M_CPU0_BCLK0_DN";
54"CLK_100M_CPU0_BCLK0_DP";
55"CLK_100M_CPU0_BCLK1_DN";
56"PU_CPU0_SAFE_MODE_BOOT";
57"PD_CPU0_KSFC_DIS";
58"PD_PIROM_CPU0_ADDR0";
59"PU_CPU0_LEGACY_SKT";
60"XDP_CPU_PRDY_N";
61"PD_CPU0_TEST13";
62"PD_CPU0_TEST12";
63"PD_CPU0_TEST14";
64"XDP_CPU_PREQ_N";
65"PD_PIROM_CPU0_ADDR2";
66"PD_PIROM_CPU0_ADDR1";
67"H_CPU0_ERR1_G_N";
68"FM_CPU0_PROC_ID1";
69"FM_CPU0_PKGID1";
70"H_PM_SYNC_GTL_R1";
71"H_PMSYNC_CLK_24M_CPU0";
72"H_CPU0_ERR0_G_N";
73"H_PM_SYNC_GTL";
74"PD_CPU0_EAR_N";
75"RST_CPU0_G_N";
76"M_ABC_RST_N";
77"TP_CPU0_PROCDIS_G_N";
78"H_CPU0_PROCHOT_G_N";
79"PU_CPU0_TXT_AGENT";
80"PD_CPU0_TXT_PLTEN";
81"PD_CPU0_BIST_ENABLE";
82"H_CPU0_FAST_WAKE_N";
83"A_CPU0_ABC_RCOMP0";
84"M_C_CPU_VREF";
85"M_A_CPU_VREF";
86"A_CPU0_ABC_RCOMP1";
87"A_CPU0_DEF_RCOMP2";
88"A_CPU0_DEF_RCOMP1";
89"A_CPU0_DEF_RCOMP0";
90"A_CPU0_PE3_RBIAS";
91"A_CPU0_PE012_RBIAS";
92"A_CPU0_UPI2_RBIAS";
93"A_CPU0_UPI01_RBIAS";
94"XDP_CPU_OBSFN_B0_MBP6_N";
95"XDP_CPU_MBP1_N";
96"XDP_CPU_TDI";
97"XDP_CPU_TMS";
98"XDP_CPU0_TDO";
99"FM_CPU0_SKTOCC_LVT3_N";
100"PECI_CPU_G";
101"SVID_CLK1_CPU0";
102"SVID_ALERT1_CPU0_N";
103"SVID_ALERT0_CPU0_N";
104"SVID_CLK0_CPU0";
105"H_PMSYNC_CLK_24M";
106"SVID_DIO0_CPU0";
107"SVID_ALERT1_CPU0_R_N";
108"H_CPU0_ERR2_G_N";
109"TP_CPU0_SOCKET_ID_2";
110"H_CPU0_CATERR_G_N";
111"H_CPU0_BMCINIT";
112"PU_CPU0_FRMAGENT";
113"H_CPU0_THERMTRIP_G_N";
%"RES"
"1","(-2000,3750)","0","mstr_discrete","I149";
;
CDS_SEC"1"
LOCATION"R6N10"
PART_NUMBER"G21796-271"
PACK_TYPE"0402"
VALUE"221"
TOLERANCE"1.0%"
WATTAGE"1/16W"
CDS_LOCATION"R6N10"
BOM_COST"PROC_SIDEBAND"
CDS_LIB"mstr_discrete"
MATERIAL"CHIP"
ROOM"CPU0"
SEC"1"
SEC_TYPE"0402";
"B"
$PN"2"16;
"A"
$PN"1"103;
%"RES"
"1","(-2000,3800)","0","mstr_discrete","I150";
;
CDS_SEC"1"
LOCATION"R6N12"
PACK_TYPE"0402"
TOLERANCE"5%"
PART_NUMBER"G21497-005"
VALUE"0.0"
WATTAGE"1/16W"
SEC_TYPE"0402"
SEC"1"
ROOM"CPU0"
CDS_LIB"mstr_discrete"
BOM_COST"PROC_SIDEBAND"
MATERIAL"CHIP"
CDS_LOCATION"R6N12";
"B"
$PN"2"18;
"A"
$PN"1"104;
%"RES"
"1","(-2000,3850)","0","mstr_discrete","I151";
;
CDS_SEC"1"
PART_NUMBER"G21497-005"
LOCATION"R6N11"
TOLERANCE"5%"
PACK_TYPE"0402"
WATTAGE"1/16W"
VALUE"0.0"
SEC_TYPE"0402"
SEC"1"
ROOM"CPU0"
CDS_LIB"mstr_discrete"
BOM_COST"PROC_SIDEBAND"
MATERIAL"CHIP"
CDS_LOCATION"R6N11";
"B"
$PN"2"17;
"A"
$PN"1"106;
%"RES"
"1","(-2000,3900)","0","mstr_discrete","I152";
;
CDS_SEC"1"
PACK_TYPE"0402"
LOCATION"R6B3"
PART_NUMBER"G21796-271"
WATTAGE"1/16W"
TOLERANCE"1.0%"
VALUE"221"
CDS_LOCATION"R6B3"
CDS_LIB"mstr_discrete"
BOM_COST"PROC_SIDEBAND"
ROOM"CPU0"
SEC_TYPE"0402"
SEC"1"
MATERIAL"CHIP";
"B"
$PN"2"107;
"A"
$PN"1"102;
%"RES"
"1","(-2000,3950)","0","mstr_discrete","I153";
;
CDS_SEC"1"
PACK_TYPE"0402"
PART_NUMBER"G21497-005"
LOCATION"R6B5"
TOLERANCE"5%"
VALUE"0.0"
WATTAGE"1/16W"
CDS_LOCATION"R6B5"
CDS_LIB"mstr_discrete"
BOM_COST"PROC_SIDEBAND"
MATERIAL"CHIP"
SEC_TYPE"0402"
SEC"1"
ROOM"CPU0";
"B"
$PN"2"19;
"A"
$PN"1"101;
%"RES"
"1","(-2000,4000)","0","mstr_discrete","I154";
;
CDS_SEC"1"
TOLERANCE"5%"
LOCATION"R6B4"
PART_NUMBER"G21497-005"
VALUE"0.0"
PACK_TYPE"0402"
WATTAGE"1/16W"
CDS_LOCATION"R6B4"
CDS_LIB"mstr_discrete"
BOM_COST"PROC_SIDEBAND"
MATERIAL"CHIP"
ROOM"CPU0"
SEC_TYPE"0402"
SEC"1";
"B"
$PN"2"20;
"A"
$PN"1"14;
%"PVCCIO_CPU0"
"1","(-900,4650)","0","mstr_symbols","I158";
;
CDS_LIB"mstr_symbols"
VOLTAGE"1.1V"
BODY_TYPE"PLUMBING"
HDL_POWER"PVCCIO_CPU0";
"G\NAC"1;
%"RES"
"2","(-1000,4300)","0","mstr_discrete","I159";
;
CDS_SEC"1"
PACK_TYPE"0402"
WATTAGE"1/16W"
TOLERANCE"1%"
PART_NUMBER"G21796-017"
MATERIAL"CHIP"
VALUE"100.0"
LOCATION"R6B2"
CDS_LOCATION"R6B2"
SEC_TYPE"0402"
SEC"1"
CDS_LIB"mstr_discrete"
BOM_COST"PROC_SIDEBAND"
ROOM"CPU0";
"A"
$PN"1"1;
"B"
$PN"2"20;
%"RES"
"2","(-750,4300)","0","mstr_discrete","I161";
;
CDS_SEC"1"
VALUE"49.9"
PART_NUMBER"G21796-047"
PACK_TYPE"0402"
LOCATION"R6B1"
WATTAGE"1/16W"
TOLERANCE"1%"
MATERIAL"CHIP"
SEC"1"
CDS_LOCATION"R6B1"
SEC_TYPE"0402"
BOM_COST"PROC_SIDEBAND"
CDS_LIB"mstr_discrete"
ROOM"CPU0";
"A"
$PN"1"1;
"B"
$PN"2"107;
%"RES"
"2","(-1000,3500)","0","mstr_discrete","I163";
;
CDS_SEC"1"
PACK_TYPE"0402"
PART_NUMBER"G21796-017"
MATERIAL"CHIP"
WATTAGE"1/16W"
LOCATION"R6N2"
VALUE"100.0"
TOLERANCE"1%"
SEC_TYPE"0402"
SEC"1"
CDS_LOCATION"R6N2"
BOM_COST"PROC_SIDEBAND"
CDS_LIB"mstr_discrete"
ROOM"CPU0";
"A"
$PN"1"17;
"B"
$PN"2"6;
%"RES"
"2","(-750,3500)","0","mstr_discrete","I164";
;
CDS_SEC"1"
VALUE"49.9"
TOLERANCE"1%"
LOCATION"R6N1"
WATTAGE"1/16W"
MATERIAL"CHIP"
PACK_TYPE"0402"
PART_NUMBER"G21796-047"
SEC_TYPE"0402"
SEC"1"
CDS_LOCATION"R6N1"
CDS_LIB"mstr_discrete"
BOM_COST"PROC_SIDEBAND"
ROOM"CPU0";
"A"
$PN"1"16;
"B"
$PN"2"6;
%"RES"
"2","(-6625,2875)","2","mstr_discrete","I177";
;
CDS_SEC"1"
PART_NUMBER"G21796-365"
TOLERANCE"1%"
WATTAGE"1/16W"
MATERIAL"CHIP"
PACK_TYPE"0402"
LOCATION"R5D1"
VALUE"90.9"
ROOM"CPU0"
BOM_COST"PROC_SOCKET"
SEC_TYPE"0402"
SEC"1"
CDS_LIB"mstr_discrete"
CDS_LOCATION"R5D1";
"A"
$PN"1"89;
"B"
$PN"2"2;
%"RES"
"2","(-6875,2925)","2","mstr_discrete","I178";
;
CDS_SEC"1"
LOCATION"R5D2"
PART_NUMBER"G21796-365"
TOLERANCE"1%"
MATERIAL"CHIP"
VALUE"90.9"
WATTAGE"1/16W"
PACK_TYPE"0402"
SEC_TYPE"0402"
BOM_COST"PROC_SOCKET"
SEC"1"
ROOM"CPU0"
CDS_LOCATION"R5D2"
CDS_LIB"mstr_discrete";
"A"
$PN"1"88;
"B"
$PN"2"2;
%"RES"
"2","(-7125,2925)","2","mstr_discrete","I179";
;
CDS_SEC"1"
MATERIAL"CHIP"
PART_NUMBER"G21796-017"
PACK_TYPE"0402"
WATTAGE"1/16W"
LOCATION"R6D1"
TOLERANCE"1%"
VALUE"100.0"
BOM_COST"PROC_SOCKET"
ROOM"CPU0"
CDS_LIB"mstr_discrete"
SEC_TYPE"0402"
SEC"1"
CDS_LOCATION"R6D1";
"A"
$PN"1"87;
"B"
$PN"2"2;
%"RES"
"2","(-7350,2925)","2","mstr_discrete","I180";
;
CDS_SEC"1"
LOCATION"R4P8"
TOLERANCE"1%"
PACK_TYPE"0402"
VALUE"90.9"
WATTAGE"1/16W"
MATERIAL"CHIP"
PART_NUMBER"G21796-365"
SEC_TYPE"0402"
BOM_COST"PROC_SOCKET"
SEC"1"
ROOM"CPU0"
CDS_LOCATION"R4P8"
CDS_LIB"mstr_discrete";
"A"
$PN"1"83;
"B"
$PN"2"2;
%"RES"
"2","(-7575,3000)","2","mstr_discrete","I181";
;
CDS_SEC"1"
LOCATION"R4P10"
VALUE"90.9"
TOLERANCE"1%"
MATERIAL"CHIP"
PACK_TYPE"0402"
PART_NUMBER"G21796-365"
WATTAGE"1/16W"
SEC_TYPE"0402"
BOM_COST"PROC_SOCKET"
ROOM"CPU0"
CDS_LOCATION"R4P10"
SEC"1"
CDS_LIB"mstr_discrete";
"A"
$PN"1"86;
"B"
$PN"2"2;
%"RES"
"2","(-7800,3000)","2","mstr_discrete","I182";
;
CDS_SEC"1"
LOCATION"R4P11"
VALUE"100.0"
TOLERANCE"1%"
MATERIAL"CHIP"
PART_NUMBER"G21796-017"
PACK_TYPE"0402"
WATTAGE"1/16W"
ROOM"CPU0"
CDS_LOCATION"R4P11"
SEC"1"
BOM_COST"PROC_SOCKET"
SEC_TYPE"0402"
CDS_LIB"mstr_discrete";
"A"
$PN"1"13;
"B"
$PN"2"2;
%"GND"
"1","(-7800,2600)","0","mstr_symbols","I183";
;
CDS_LIB"mstr_symbols"
SIZE"1B"
VOLTAGE"0.0V"
BODY_TYPE"PLUMBING"
HDL_POWER"GND";
"A\NAC"2;
%"RES"
"2","(-7350,2000)","2","mstr_discrete","I184";
;
CDS_SEC"1"
WATTAGE"1/16W"
MATERIAL"CHIP"
PACK_TYPE"0402"
PART_NUMBER"G21796-047"
LOCATION"R6D11"
VALUE"49.9"
TOLERANCE"1%"
ROOM"CPU0"
CDS_LOCATION"R6D11"
SEC"1"
SEC_TYPE"0402"
BOM_COST"PROC_SOCKET"
CDS_LIB"mstr_discrete";
"A"
$PN"1"93;
"B"
$PN"2"3;
%"RES"
"2","(-7575,2100)","2","mstr_discrete","I186";
;
CDS_SEC"1"
TOLERANCE"1%"
LOCATION"R4P3"
VALUE"49.9"
WATTAGE"1/16W"
MATERIAL"CHIP"
PACK_TYPE"0402"
PART_NUMBER"G21796-047"
SEC"1"
SEC_TYPE"0402"
BOM_COST"PROC_SOCKET"
ROOM"CPU0"
CDS_LOCATION"R4P3"
CDS_LIB"mstr_discrete";
"A"
$PN"1"91;
"B"
$PN"2"3;
%"GND"
"1","(-7800,1725)","0","mstr_symbols","I187";
;
VOLTAGE"0.0V"
SIZE"1B"
CDS_LIB"mstr_symbols"
BODY_TYPE"PLUMBING"
HDL_POWER"GND";
"A\NAC"3;
%"RES"
"2","(-7800,2200)","2","mstr_discrete","I188";
;
CDS_SEC"1"
TOLERANCE"1%"
MATERIAL"CHIP"
VALUE"49.9"
LOCATION"R4P2"
WATTAGE"1/16W"
PART_NUMBER"G21796-047"
PACK_TYPE"0402"
SEC"1"
BOM_COST"PROC_SOCKET"
SEC_TYPE"0402"
CDS_LOCATION"R4P2"
ROOM"CPU0"
CDS_LIB"mstr_discrete";
"A"
$PN"1"90;
"B"
$PN"2"3;
%"RES"
"2","(-7125,2000)","2","mstr_discrete","I189";
;
CDS_SEC"1"
VALUE"49.9"
TOLERANCE"1%"
PACK_TYPE"0402"
MATERIAL"CHIP"
PART_NUMBER"G21796-047"
LOCATION"R4P4"
WATTAGE"1/16W"
BOM_COST"PROC_SOCKET"
ROOM"CPU0"
SEC_TYPE"0402"
SEC"1"
CDS_LOCATION"R4P4"
CDS_LIB"mstr_discrete";
"A"
$PN"1"92;
"B"
$PN"2"3;
%"RES"
"2","(-6900,2000)","2","mstr_discrete","I204";
;
CDS_SEC"1"
VALUE"49.9"
LOCATION"R6D2"
TOLERANCE"1%"
WATTAGE"1/16W"
PACK_TYPE"0402"
PART_NUMBER"G21796-047"
MATERIAL"CHIP"
BOM_COST"PROC_SOCKET"
ROOM"CPU0"
CDS_LOCATION"R6D2"
SEC"1"
SEC_TYPE"0402"
CDS_LIB"mstr_discrete";
"A"
$PN"1"46;
"B"
$PN"2"3;
%"SOCKET_P_MECH_A"
"1","(-7525,4450)","0","chpset_lib","I216";
;
PACK_TYPE"RIGHT"
MATERIAL"PLASTIC"
PART_NUMBER"H37604-101"
LOCATION"XRU1"
SKT_NUMBER"P0"
CDS_LIB"chpset_lib"
ROOM"CPU0"
BOM_COST"PROC_SOCKET"
CDS_LOCATION"XRU1";
%"SOCKET_P_MECH_A"
"1","(-7525,4150)","0","chpset_lib","I217";
;
PACK_TYPE"LEFT"
SKT_NUMBER"P0"
PART_NUMBER"H37604-201"
LOCATION"XLU1"
MATERIAL"PLASTIC"
CDS_LIB"chpset_lib"
ROOM"CPU0"
CDS_LOCATION"XLU1"
BOM_COST"PROC_SOCKET";
%"RES"
"1","(-2075,4200)","0","mstr_discrete","I219";
;
CDS_SEC"1"
WATTAGE"1/16W"
TOLERANCE"1%"
LOCATION"R4P19"
PART_NUMBER"G21796-047"
VALUE"49.9"
MATERIAL"CHIP"
PACK_TYPE"0402"
ROOM"CPU0"
SEC"1"
BOM_COST"PROC_SOCKET"
SEC_TYPE"0402"
CDS_LOCATION"R4P19"
CDS_LIB"mstr_discrete";
"B"
$PN"2"105;
"A"
$PN"1"71;
%"RES"
"2","(-1700,2700)","0","mstr_discrete","I227";
;
CDS_SEC"1"
PACK_TYPE"0402"
LOCATION"R5N2"
MATERIAL"CHIP"
WATTAGE"1/16W"
TOLERANCE"1%"
PART_NUMBER"G21796-336"
VALUE"1.8K"
CDS_LOCATION"R5N2"
SEC"1"
SEC_TYPE"0402"
BOM_COST"PROC_SIDEBAND"
CDS_LIB"mstr_discrete"
ROOM"CPU0";
"A"
$PN"1"4;
"B"
$PN"2"68;
%"P3V3_STBY"
"1","(-700,3000)","0","mstr_symbols","I228";
;
VOLTAGE"3.3V"
CDS_LIB"mstr_symbols"
SIZE"1B"
BODY_TYPE"PLUMBING"
HDL_POWER"P3V3_STBY";
"G\NAC"4;
%"RES"
"2","(-700,2700)","0","mstr_discrete","I238";
;
CDS_SEC"1"
PART_NUMBER"G21796-016"
WATTAGE"1/16W"
LOCATION"R5N1"
VALUE"10.0K"
PACK_TYPE"0402"
MATERIAL"CHIP"
TOLERANCE"1%"
SEC_TYPE"0402"
SEC"1"
CDS_LOCATION"R5N1"
BOM_COST"PROC_SIDEBAND"
CDS_LIB"mstr_discrete"
ROOM"CPU0";
"A"
$PN"1"4;
"B"
$PN"2"21;
%"RES"
"2","(-950,2700)","0","mstr_discrete","I239";
;
CDS_SEC"1"
PART_NUMBER"G21796-016"
WATTAGE"1/16W"
PACK_TYPE"0402"
VALUE"10.0K"
TOLERANCE"1%"
MATERIAL"CHIP"
LOCATION"R5N5"
SEC"1"
SEC_TYPE"0402"
CDS_LOCATION"R5N5"
CDS_LIB"mstr_discrete"
BOM_COST"PROC_SIDEBAND"
ROOM"CPU0";
"A"
$PN"1"4;
"B"
$PN"2"69;
%"RES"
"2","(-1200,2700)","0","mstr_discrete","I240";
;
CDS_SEC"1"
MATERIAL"CHIP"
WATTAGE"1/16W"
VALUE"10.0K"
LOCATION"R5N3"
PART_NUMBER"G21796-016"
TOLERANCE"1%"
PACK_TYPE"0402"
SEC"1"
SEC_TYPE"0402"
CDS_LOCATION"R5N3"
CDS_LIB"mstr_discrete"
BOM_COST"PROC_SIDEBAND"
ROOM"CPU0";
"A"
$PN"1"4;
"B"
$PN"2"15;
%"RES"
"2","(-1450,2700)","0","mstr_discrete","I241";
;
CDS_SEC"1"
MATERIAL"CHIP"
PACK_TYPE"0402"
PART_NUMBER"G21796-336"
LOCATION"R5N4"
VALUE"1.8K"
TOLERANCE"1%"
WATTAGE"1/16W"
SEC"1"
CDS_LOCATION"R5N4"
SEC_TYPE"0402"
CDS_LIB"mstr_discrete"
BOM_COST"PROC_SIDEBAND"
ROOM"CPU0";
"A"
$PN"1"4;
"B"
$PN"2"24;
%"P3V3_STBY"
"1","(-1075,1725)","0","mstr_symbols","I243";
;
VOLTAGE"3.3V"
CDS_LIB"mstr_symbols"
SIZE"1B"
BODY_TYPE"PLUMBING"
HDL_POWER"P3V3_STBY";
"G\NAC"5;
%"RES"
"1","(-2075,4250)","0","mstr_discrete","I244";
;
CDS_SEC"1"
PACK_TYPE"0402"
MATERIAL"CHIP"
WATTAGE"1/16W"
TOLERANCE"1%"
VALUE"49.9"
LOCATION"R4P18"
PART_NUMBER"G21796-047"
SEC_TYPE"0402"
BOM_COST"PROC_SIDEBAND"
SEC"1"
ROOM"CPU0"
CDS_LIB"mstr_discrete"
CDS_LOCATION"R4P18";
"B"
$PN"2"73;
"A"
$PN"1"70;
%"PVCCIO_CPU0"
"1","(-375,3400)","0","mstr_symbols","I257";
;
VOLTAGE"1.1V"
CDS_LIB"mstr_symbols"
BODY_TYPE"PLUMBING"
HDL_POWER"PVCCIO_CPU0";
"G\NAC"6;
%"RES"
"2","(-1075,1450)","0","mstr_discrete","I258";
;
CDS_SEC"1"
TOLERANCE"1%"
LOCATION"R4R5"
MATERIAL"CHIP"
PART_NUMBER"G21796-072"
PACK_TYPE"0402"
WATTAGE"1/16W"
VALUE"4.75K"
SEC_TYPE"0402"
SEC"1"
ROOM"CPU0"
CDS_LOCATION"R4R5"
CDS_LIB"mstr_discrete";
"A"
$PN"1"5;
"B"
$PN"2"99;
%"SKX_EXT_B"
"1","(-4075,2850)","0","chpset_lib","I259";
;
CDS_SEC"1"
LOCATION"U5D1"
MATERIAL"IC"
PART_NUMBER"TBD"
CDS_LIB"chpset_lib"
SEC_TYPE"BGA1"
SEC"1"
CDS_LOCATION"U5D1"
PACK_TYPE"BGA1"
ROOM"CPU0";
"UPI2_RBIAS<0>"
$PN"CL28"92;
"UPI2_RBIAS<1>"
$PN"CK29"92;
"UPI01_RBIAS<0>"
$PN"AT29"93;
"UPI01_RBIAS<1>"
$PN"AP29"93;
"TXT_PLTEN"
$PN"AV15"80;
"TXT_AGENT"
$PN"AW18"79;
"TSC_SYNC"
$PN"AM11"25;
"TRST_N"
$PN"Y13"41;
"TMS"
$PN"W14"97;
"THERMTRIP_N"
$PN"AB15"113;
"TEST_15"
$PN"AW14"57;
"TEST_14"
$PN"DC50"63;
"TEST_13"
$PN"DB51"61;
"TEST_12"
$PN"AY19"62;
"TDO"
$PN"AE14"98;
"TDI"
$PN"AC14"96;
"TCK"
$PN"AA14"42;
"SVIDDATA<0>"
$PN"DB45"106;
"SVIDDATA<1>"
$PN"DJ44"14;
"SVIDCLK<0>"
$PN"DC44"104;
"SVIDCLK<1>"
$PN"DG44"101;
"SVIDALERT_N<0>"
$PN"DE44"103;
"SVIDALERT_N<1>"
$PN"DL44"102;
"SOCKET_ID<0>"
$PN"AU22"23;
"SOCKET_ID<1>"
$PN"AU16"22;
"SOCKET_ID<2>"
$PN"AU20"109;
"SM_WP"
$PN"CV59"26;
"SMBDAT"
$PN"CW58"30;
"SMBCLK"
$PN"CT59"29;
"SKTOCC_N"
$PN"AB13"99;
"SAFE_MODE_BOOT"
$PN"AR18"56;
"RESET_N"
$PN"AP21"75;
"PWRGOOD"
$PN"BC24"11;
"PROC_ID<0>"
$PN"CY71"24;
"PROC_ID<1>"
$PN"DB71"68;
"PROCHOT_N"
$PN"AC16"78;
"PROCDIS_N"
$PN"AB17"77;
"PREQ_N"
$PN"AR12"64;
"PRDY_N"
$PN"AG16"60;
"PM_FAST_WAKE_N"
$PN"AF15"82;
"PMSYNC_CLK"
$PN"AT19"71;
"PMSYNC"
$PN"AR14"70;
"PKGID<0>"
$PN"DC72"21;
"PKGID<1>"
$PN"CW72"69;
"PKGID<2>"
$PN"DA72"15;
"PIROM_ADDR<0>"
$PN"CU58"58;
"PIROM_ADDR<1>"
$PN"CV57"66;
"PIROM_ADDR<2>"
$PN"CW56"65;
"PE_HP_SDA"
$PN"AL18"32;
"PE_HP_SCL"
$PN"AM19"31;
"PECI"
$PN"AU12"100;
"PE3_RBIAS<0>"
$PN"CP29"90;
"PE3_RBIAS<1>"
$PN"CR30"90;
"PE012_RBIAS<0>"
$PN"CN30"91;
"PE012_RBIAS<1>"
$PN"CL30"91;
"NMI"
$PN"AP11"27;
"MSMI_N"
$PN"AN20"8;
"MEM_HOT_C345_N"
$PN"AF13"36;
"MEM_HOT_C012_N"
$PN"AH13"38;
"MCP01_RBIAS<0>"
$PN"CU32"46;
"MCP01_RBIAS<1>"
$PN"CT31"46;
"LEGACY_SKT"
$PN"AE20"59;
"FRMAGENT"
$PN"AV17"112;
"ERROR_N<0>"
$PN"AJ12"72;
"ERROR_N<1>"
$PN"AK11"67;
"ERROR_N<2>"
$PN"AL12"108;
"EAR_N"
$PN"AJ14"74;
"DDR5_CAVREF"
$PN"CV61"37;
"DDR4_CAVREF"
$PN"CT61"9;
"DDR3_CAVREF"
$PN"CP61"7;
"DDR345_SPDSDA"
$PN"AD17"48;
"DDR345_SPDSCL"
$PN"AE18"50;
"DDR345_RESET_N"
$PN"DV63"39;
"DDR345_RCOMP<0>"
$PN"DC48"89;
"DDR345_RCOMP<1>"
$PN"DD47"88;
"DDR345_RCOMP<2>"
$PN"DD49"87;
"DDR345_DRAM_PWR_OK"
$PN"CR28"40;
"DDR2_CAVREF"
$PN"AH63"84;
"DDR1_CAVREF"
$PN"AK63"28;
"DDR0_CAVREF"
$PN"AJ64"85;
"DDR012_SPDSDA"
$PN"AF17"47;
"DDR012_SPDSCL"
$PN"AJ18"49;
"DDR012_RESET_N"
$PN"U64"76;
"DDR012_RCOMP<0>"
$PN"Y43"83;
"DDR012_RCOMP<1>"
$PN"AB43"86;
"DDR012_RCOMP<2>"
$PN"AC42"13;
"DDR012_DRAM_PWR_OK"
$PN"AN30"10;
"CATERR_N"
$PN"AL14"110;
"BPM_N<0>"
$PN"AJ10"43;
"BPM_N<1>"
$PN"AH11"95;
"BPM_N<2>"
$PN"AG10"44;
"BPM_N<3>"
$PN"AF11"45;
"BPM_N<4>"
$PN"AA12"35;
"BPM_N<5>"
$PN"Y11"34;
"BPM_N<6>"
$PN"AE12"94;
"BPM_N<7>"
$PN"AC12"33;
"BMCINIT"
$PN"BD23"111;
"BIST_ENABLE"
$PN"BA20"81;
"BCLK2_DP"
$PN"CU26"51;
"BCLK2_DN"
$PN"CT25"12;
"BCLK1_DP"
$PN"CP27"52;
"BCLK1_DN"
$PN"CR26"55;
"BCLK0_DP"
$PN"AW24"54;
"BCLK0_DN"
$PN"AU24"53;
END.
